(kicad_pcb
	(version 20260206)
	(generator "pcbnew")
	(generator_version "10.0")
	(general
		(thickness 1.6)
		(legacy_teardrops no)
	)
	(paper "A4")
	(title_block
		(title "01162023_DA0F0TEBIF0_F0T_Expander_BD_F_brd_V02_OCP.brd")
		(comment 1 "Grand Teton / footprints 911-917 of 9728")
	)
	(layers
		(0 "F.Cu" signal "TOP")
		(4 "In1.Cu" signal "GND")
		(6 "In2.Cu" signal "VCC")
		(8 "In3.Cu" signal "VCC1")
		(10 "In4.Cu" signal "GND1")
		(12 "In5.Cu" signal "IN1")
		(14 "In6.Cu" signal "GND2")
		(16 "In7.Cu" signal "IN2")
		(18 "In8.Cu" signal "GND3")
		(20 "In9.Cu" signal "IN3")
		(22 "In10.Cu" signal "GND4")
		(24 "In11.Cu" signal "IN4")
		(26 "In12.Cu" signal "GND5")
		(28 "In13.Cu" signal "IN5")
		(30 "In14.Cu" signal "GND6")
		(32 "In15.Cu" signal "IN6")
		(34 "In16.Cu" signal "GND7")
		(2 "B.Cu" signal "BOTTOM")
		(9 "F.Adhes" user "F.Adhesive")
		(11 "B.Adhes" user "B.Adhesive")
		(13 "F.Paste" user "Package Geometry/Pastemask Top")
		(15 "B.Paste" user "Package Geometry/Pastemask Bottom")
		(5 "F.SilkS" user "Ref Des/Silkscreen Top")
		(7 "B.SilkS" user "Ref Des/Silkscreen Bottom")
		(1 "F.Mask" user "Board Geometry/Soldermask Top")
		(3 "B.Mask" user "Board Geometry/Soldermask Bottom")
		(17 "Dwgs.User" user "User.Drawings")
		(19 "Cmts.User" user "User.Comments")
		(21 "Eco1.User" user "User.Eco1")
		(23 "Eco2.User" user "User.Eco2")
		(25 "Edge.Cuts" user "Board Geometry/Outline")
		(27 "Margin" user)
		(31 "F.CrtYd" user "Package Geometry/Place Bound Top")
		(29 "B.CrtYd" user "Package Geometry/Place Bound Bottom")
		(35 "F.Fab" user "Ref Des/Assembly Top")
		(33 "B.Fab" user "Ref Des/Assembly Bottom")
	)
	(footprint ""
		(layer "F.Cu")
		(at 123.67514 -99.463606 180)
		(property "Reference" "R1566"
			(at 0 0 180)
			(layer "F.SilkS")
			(hide yes)
			(effects
				(font
					(size 1.27 1.27)
				)
			)
		)
		(property "Value" ""
			(at 0 0 180)
			(layer "F.Fab")
			(effects
				(font
					(size 1.27 1.27)
				)
			)
		)
		(duplicate_pad_numbers_are_jumpers no)
		(fp_line
			(start 0.7874 0.4064)
			(end -0.7874 0.4064)
			(stroke
				(width 0.1524)
				(type default)
			)
			(layer "F.SilkS")
		)
		(fp_line
			(start 0.7874 -0.4064)
			(end 0.7874 0.4064)
			(stroke
				(width 0.1524)
				(type default)
			)
			(layer "F.SilkS")
		)
		(fp_line
			(start -0.7874 0.4064)
			(end -0.7874 -0.4064)
			(stroke
				(width 0.1524)
				(type default)
			)
			(layer "F.SilkS")
		)
		(fp_line
			(start -0.7874 -0.4064)
			(end 0.7874 -0.4064)
			(stroke
				(width 0.1524)
				(type default)
			)
			(layer "F.SilkS")
		)
		(fp_line
			(start 0.67945 0.3048)
			(end 0.120396 0.3048)
			(stroke
				(width 0.1)
				(type default)
			)
			(layer "F.Fab")
		)
		(fp_line
			(start 0.67945 -0.3048)
			(end 0.67945 0.3048)
			(stroke
				(width 0.1)
				(type default)
			)
			(layer "F.Fab")
		)
		(fp_line
			(start 0.12065 -0.2794)
			(end 0.12065 -0.3048)
			(stroke
				(width 0.1)
				(type default)
			)
			(layer "F.Fab")
		)
		(fp_line
			(start 0.12065 -0.3048)
			(end 0.67945 -0.3048)
			(stroke
				(width 0.1)
				(type default)
			)
			(layer "F.Fab")
		)
		(fp_line
			(start 0.120396 0.3048)
			(end 0.120396 0.2794)
			(stroke
				(width 0.1)
				(type default)
			)
			(layer "F.Fab")
		)
		(fp_line
			(start 0.120396 0.2794)
			(end -0.12065 0.2794)
			(stroke
				(width 0.1)
				(type default)
			)
			(layer "F.Fab")
		)
		(fp_line
			(start -0.12065 0.3048)
			(end -0.67945 0.3048)
			(stroke
				(width 0.1)
				(type default)
			)
			(layer "F.Fab")
		)
		(fp_line
			(start -0.12065 0.2794)
			(end -0.12065 0.3048)
			(stroke
				(width 0.1)
				(type default)
			)
			(layer "F.Fab")
		)
		(fp_line
			(start -0.12065 -0.2794)
			(end 0.12065 -0.2794)
			(stroke
				(width 0.1)
				(type default)
			)
			(layer "F.Fab")
		)
		(fp_line
			(start -0.12065 -0.305054)
			(end -0.12065 -0.2794)
			(stroke
				(width 0.1)
				(type default)
			)
			(layer "F.Fab")
		)
		(fp_line
			(start -0.67945 0.3048)
			(end -0.67945 -0.305054)
			(stroke
				(width 0.1)
				(type default)
			)
			(layer "F.Fab")
		)
		(fp_line
			(start -0.67945 -0.305054)
			(end -0.12065 -0.305054)
			(stroke
				(width 0.1)
				(type default)
			)
			(layer "F.Fab")
		)
		(pad "1" smd circle
			(at -0.40005 0 180)
			(size 0 0)
			(layers "F.Cu" "F.Mask" "F.Paste")
			(net "BIC_I2C9_SSD_MUX0_A0")
		)
		(pad "2" smd circle
			(at 0.40005 0 180)
			(size 0 0)
			(layers "F.Cu" "F.Mask" "F.Paste")
			(net "GND")
		)
	)
	(footprint ""
		(layer "F.Cu")
		(at 127.381508 -350.098614 90)
		(property "Reference" "C354"
			(at 0 0 90)
			(layer "F.SilkS")
			(hide yes)
			(effects
				(font
					(size 1.27 1.27)
				)
			)
		)
		(property "Value" ""
			(at 0 0 90)
			(layer "F.Fab")
			(effects
				(font
					(size 1.27 1.27)
				)
			)
		)
		(duplicate_pad_numbers_are_jumpers no)
		(fp_line
			(start 0.299974 -0.150114)
			(end 0.299974 0.150114)
			(stroke
				(width 0.1)
				(type default)
			)
			(layer "F.Fab")
		)
		(fp_line
			(start -0.299974 -0.150114)
			(end 0.299974 -0.150114)
			(stroke
				(width 0.1)
				(type default)
			)
			(layer "F.Fab")
		)
		(fp_line
			(start 0.299974 0.150114)
			(end -0.299974 0.150114)
			(stroke
				(width 0.1)
				(type default)
			)
			(layer "F.Fab")
		)
		(fp_line
			(start -0.299974 0.150114)
			(end -0.299974 -0.150114)
			(stroke
				(width 0.1)
				(type default)
			)
			(layer "F.Fab")
		)
		(pad "1" smd rect
			(at -0.2667 0 90)
			(size 0.3048 0.381)
			(layers "F.Cu" "F.Mask" "F.Paste")
			(net "P5E_PEX1_STN6_TX_DP<104>")
		)
		(pad "2" smd rect
			(at 0.2667 0 90)
			(size 0.3048 0.381)
			(layers "F.Cu" "F.Mask" "F.Paste")
			(net "P5E_PEX1_STN6_TX_C_DP<104>")
		)
	)
	(footprint ""
		(layer "F.Cu")
		(at 97.25787 -72.766682 90)
		(property "Reference" "PC653"
			(at 0 0 90)
			(layer "F.SilkS")
			(hide yes)
			(effects
				(font
					(size 1.27 1.27)
				)
			)
		)
		(property "Value" ""
			(at 0 0 90)
			(layer "F.Fab")
			(effects
				(font
					(size 1.27 1.27)
				)
			)
		)
		(duplicate_pad_numbers_are_jumpers no)
		(fp_line
			(start 0.7874 -0.4064)
			(end 0.7874 0.4064)
			(stroke
				(width 0.1524)
				(type default)
			)
			(layer "F.SilkS")
		)
		(fp_line
			(start -0.7874 -0.4064)
			(end 0.7874 -0.4064)
			(stroke
				(width 0.1524)
				(type default)
			)
			(layer "F.SilkS")
		)
		(fp_line
			(start 0.7874 0.4064)
			(end -0.7874 0.4064)
			(stroke
				(width 0.1524)
				(type default)
			)
			(layer "F.SilkS")
		)
		(fp_line
			(start -0.7874 0.4064)
			(end -0.7874 -0.4064)
			(stroke
				(width 0.1524)
				(type default)
			)
			(layer "F.SilkS")
		)
		(fp_line
			(start -0.12065 -0.305054)
			(end -0.12065 -0.2794)
			(stroke
				(width 0.1)
				(type default)
			)
			(layer "F.Fab")
		)
		(fp_line
			(start -0.67945 -0.305054)
			(end -0.12065 -0.305054)
			(stroke
				(width 0.1)
				(type default)
			)
			(layer "F.Fab")
		)
		(fp_line
			(start 0.67945 -0.3048)
			(end 0.67945 0.3048)
			(stroke
				(width 0.1)
				(type default)
			)
			(layer "F.Fab")
		)
		(fp_line
			(start 0.12065 -0.3048)
			(end 0.67945 -0.3048)
			(stroke
				(width 0.1)
				(type default)
			)
			(layer "F.Fab")
		)
		(fp_line
			(start 0.12065 -0.2794)
			(end 0.12065 -0.3048)
			(stroke
				(width 0.1)
				(type default)
			)
			(layer "F.Fab")
		)
		(fp_line
			(start -0.12065 -0.2794)
			(end 0.12065 -0.2794)
			(stroke
				(width 0.1)
				(type default)
			)
			(layer "F.Fab")
		)
		(fp_line
			(start 0.120396 0.2794)
			(end -0.12065 0.2794)
			(stroke
				(width 0.1)
				(type default)
			)
			(layer "F.Fab")
		)
		(fp_line
			(start -0.12065 0.2794)
			(end -0.12065 0.3048)
			(stroke
				(width 0.1)
				(type default)
			)
			(layer "F.Fab")
		)
		(fp_line
			(start 0.67945 0.3048)
			(end 0.120396 0.3048)
			(stroke
				(width 0.1)
				(type default)
			)
			(layer "F.Fab")
		)
		(fp_line
			(start 0.120396 0.3048)
			(end 0.120396 0.2794)
			(stroke
				(width 0.1)
				(type default)
			)
			(layer "F.Fab")
		)
		(fp_line
			(start -0.12065 0.3048)
			(end -0.67945 0.3048)
			(stroke
				(width 0.1)
				(type default)
			)
			(layer "F.Fab")
		)
		(fp_line
			(start -0.67945 0.3048)
			(end -0.67945 -0.305054)
			(stroke
				(width 0.1)
				(type default)
			)
			(layer "F.Fab")
		)
		(pad "1" smd circle
			(at -0.40005 0 90)
			(size 0 0)
			(layers "F.Cu" "F.Mask" "F.Paste")
			(net "P12V_SSD3_CO_MODE")
		)
		(pad "2" smd circle
			(at 0.40005 0 90)
			(size 0 0)
			(layers "F.Cu" "F.Mask" "F.Paste")
			(net "GND")
		)
	)
	(footprint ""
		(layer "F.Cu")
		(at 320.235834 -303.61128 90)
		(property "Reference" "R6719"
			(at 0 0 90)
			(layer "F.SilkS")
			(hide yes)
			(effects
				(font
					(size 1.27 1.27)
				)
			)
		)
		(property "Value" ""
			(at 0 0 90)
			(layer "F.Fab")
			(effects
				(font
					(size 1.27 1.27)
				)
			)
		)
		(duplicate_pad_numbers_are_jumpers no)
		(fp_line
			(start 0.7874 -0.4064)
			(end 0.7874 0.4064)
			(stroke
				(width 0.1524)
				(type default)
			)
			(layer "F.SilkS")
		)
		(fp_line
			(start -0.7874 -0.4064)
			(end 0.7874 -0.4064)
			(stroke
				(width 0.1524)
				(type default)
			)
			(layer "F.SilkS")
		)
		(fp_line
			(start 0.7874 0.4064)
			(end -0.7874 0.4064)
			(stroke
				(width 0.1524)
				(type default)
			)
			(layer "F.SilkS")
		)
		(fp_line
			(start -0.7874 0.4064)
			(end -0.7874 -0.4064)
			(stroke
				(width 0.1524)
				(type default)
			)
			(layer "F.SilkS")
		)
		(fp_line
			(start -0.12065 -0.305054)
			(end -0.12065 -0.2794)
			(stroke
				(width 0.1)
				(type default)
			)
			(layer "F.Fab")
		)
		(fp_line
			(start -0.67945 -0.305054)
			(end -0.12065 -0.305054)
			(stroke
				(width 0.1)
				(type default)
			)
			(layer "F.Fab")
		)
		(fp_line
			(start 0.67945 -0.3048)
			(end 0.67945 0.3048)
			(stroke
				(width 0.1)
				(type default)
			)
			(layer "F.Fab")
		)
		(fp_line
			(start 0.12065 -0.3048)
			(end 0.67945 -0.3048)
			(stroke
				(width 0.1)
				(type default)
			)
			(layer "F.Fab")
		)
		(fp_line
			(start 0.12065 -0.2794)
			(end 0.12065 -0.3048)
			(stroke
				(width 0.1)
				(type default)
			)
			(layer "F.Fab")
		)
		(fp_line
			(start -0.12065 -0.2794)
			(end 0.12065 -0.2794)
			(stroke
				(width 0.1)
				(type default)
			)
			(layer "F.Fab")
		)
		(fp_line
			(start 0.120396 0.2794)
			(end -0.12065 0.2794)
			(stroke
				(width 0.1)
				(type default)
			)
			(layer "F.Fab")
		)
		(fp_line
			(start -0.12065 0.2794)
			(end -0.12065 0.3048)
			(stroke
				(width 0.1)
				(type default)
			)
			(layer "F.Fab")
		)
		(fp_line
			(start 0.67945 0.3048)
			(end 0.120396 0.3048)
			(stroke
				(width 0.1)
				(type default)
			)
			(layer "F.Fab")
		)
		(fp_line
			(start 0.120396 0.3048)
			(end 0.120396 0.2794)
			(stroke
				(width 0.1)
				(type default)
			)
			(layer "F.Fab")
		)
		(fp_line
			(start -0.12065 0.3048)
			(end -0.67945 0.3048)
			(stroke
				(width 0.1)
				(type default)
			)
			(layer "F.Fab")
		)
		(fp_line
			(start -0.67945 0.3048)
			(end -0.67945 -0.305054)
			(stroke
				(width 0.1)
				(type default)
			)
			(layer "F.Fab")
		)
		(pad "1" smd circle
			(at -0.40005 0 90)
			(size 0 0)
			(layers "F.Cu" "F.Mask" "F.Paste")
			(net "SMB_PEX2_SLAVE1_SDA")
		)
		(pad "2" smd circle
			(at 0.40005 0 90)
			(size 0 0)
			(layers "F.Cu" "F.Mask" "F.Paste")
			(net "SMB_PEX2_R_SDA")
		)
	)
	(footprint ""
		(layer "F.Cu")
		(at 300.187868 -45.704252 90)
		(property "Reference" "R615"
			(at 0 0 90)
			(layer "F.SilkS")
			(hide yes)
			(effects
				(font
					(size 1.27 1.27)
				)
			)
		)
		(property "Value" ""
			(at 0 0 90)
			(layer "F.Fab")
			(effects
				(font
					(size 1.27 1.27)
				)
			)
		)
		(duplicate_pad_numbers_are_jumpers no)
		(fp_line
			(start 3.937508 -1.8796)
			(end -3.937508 -1.8796)
			(stroke
				(width 0.1524)
				(type default)
			)
			(layer "F.SilkS")
		)
		(fp_line
			(start -3.937508 -1.8796)
			(end -3.937508 1.8796)
			(stroke
				(width 0.1524)
				(type default)
			)
			(layer "F.SilkS")
		)
		(fp_line
			(start 3.937508 1.8796)
			(end 3.937508 -1.8796)
			(stroke
				(width 0.1524)
				(type default)
			)
			(layer "F.SilkS")
		)
		(fp_line
			(start -3.937508 1.8796)
			(end 3.937508 1.8796)
			(stroke
				(width 0.1524)
				(type default)
			)
			(layer "F.SilkS")
		)
		(fp_line
			(start 3.275076 -1.674876)
			(end -3.275076 -1.674876)
			(stroke
				(width 0.1)
				(type default)
			)
			(layer "F.Fab")
		)
		(fp_line
			(start -3.275076 -1.674876)
			(end -3.275076 1.674876)
			(stroke
				(width 0.1)
				(type default)
			)
			(layer "F.Fab")
		)
		(fp_line
			(start 3.275076 1.674876)
			(end 3.275076 -1.674876)
			(stroke
				(width 0.1)
				(type default)
			)
			(layer "F.Fab")
		)
		(fp_line
			(start -3.275076 1.674876)
			(end 3.275076 1.674876)
			(stroke
				(width 0.1)
				(type default)
			)
			(layer "F.Fab")
		)
		(pad "1" smd rect
			(at -2.350008 0 90)
			(size 2.921 3.5052)
			(layers "F.Cu" "F.Mask" "F.Paste")
			(net "P12V_SSD10")
		)
		(pad "2" smd rect
			(at 2.350008 0 90)
			(size 2.921 3.5052)
			(layers "F.Cu" "F.Mask" "F.Paste")
			(net "P12V_SSD10_R")
		)
	)
	(footprint ""
		(layer "F.Cu")
		(at 370.185696 -27.092148 -90)
		(property "Reference" "R5751"
			(at 0 0 270)
			(layer "F.SilkS")
			(hide yes)
			(effects
				(font
					(size 1.27 1.27)
				)
			)
		)
		(property "Value" ""
			(at 0 0 270)
			(layer "F.Fab")
			(effects
				(font
					(size 1.27 1.27)
				)
			)
		)
		(duplicate_pad_numbers_are_jumpers no)
		(fp_line
			(start -0.7874 0.4064)
			(end -0.7874 -0.4064)
			(stroke
				(width 0.1524)
				(type default)
			)
			(layer "F.SilkS")
		)
		(fp_line
			(start 0.7874 0.4064)
			(end -0.7874 0.4064)
			(stroke
				(width 0.1524)
				(type default)
			)
			(layer "F.SilkS")
		)
		(fp_line
			(start -0.7874 -0.4064)
			(end 0.7874 -0.4064)
			(stroke
				(width 0.1524)
				(type default)
			)
			(layer "F.SilkS")
		)
		(fp_line
			(start 0.7874 -0.4064)
			(end 0.7874 0.4064)
			(stroke
				(width 0.1524)
				(type default)
			)
			(layer "F.SilkS")
		)
		(fp_line
			(start -0.67945 0.3048)
			(end -0.67945 -0.305054)
			(stroke
				(width 0.1)
				(type default)
			)
			(layer "F.Fab")
		)
		(fp_line
			(start -0.12065 0.3048)
			(end -0.67945 0.3048)
			(stroke
				(width 0.1)
				(type default)
			)
			(layer "F.Fab")
		)
		(fp_line
			(start 0.120396 0.3048)
			(end 0.120396 0.2794)
			(stroke
				(width 0.1)
				(type default)
			)
			(layer "F.Fab")
		)
		(fp_line
			(start 0.67945 0.3048)
			(end 0.120396 0.3048)
			(stroke
				(width 0.1)
				(type default)
			)
			(layer "F.Fab")
		)
		(fp_line
			(start -0.12065 0.2794)
			(end -0.12065 0.3048)
			(stroke
				(width 0.1)
				(type default)
			)
			(layer "F.Fab")
		)
		(fp_line
			(start 0.120396 0.2794)
			(end -0.12065 0.2794)
			(stroke
				(width 0.1)
				(type default)
			)
			(layer "F.Fab")
		)
		(fp_line
			(start -0.12065 -0.2794)
			(end 0.12065 -0.2794)
			(stroke
				(width 0.1)
				(type default)
			)
			(layer "F.Fab")
		)
		(fp_line
			(start 0.12065 -0.2794)
			(end 0.12065 -0.3048)
			(stroke
				(width 0.1)
				(type default)
			)
			(layer "F.Fab")
		)
		(fp_line
			(start 0.12065 -0.3048)
			(end 0.67945 -0.3048)
			(stroke
				(width 0.1)
				(type default)
			)
			(layer "F.Fab")
		)
		(fp_line
			(start 0.67945 -0.3048)
			(end 0.67945 0.3048)
			(stroke
				(width 0.1)
				(type default)
			)
			(layer "F.Fab")
		)
		(fp_line
			(start -0.67945 -0.305054)
			(end -0.12065 -0.305054)
			(stroke
				(width 0.1)
				(type default)
			)
			(layer "F.Fab")
		)
		(fp_line
			(start -0.12065 -0.305054)
			(end -0.12065 -0.2794)
			(stroke
				(width 0.1)
				(type default)
			)
			(layer "F.Fab")
		)
		(pad "1" smd circle
			(at -0.40005 0 270)
			(size 0 0)
			(layers "F.Cu" "F.Mask" "F.Paste")
			(net "P3V3_SSD12")
		)
		(pad "2" smd circle
			(at 0.40005 0 270)
			(size 0 0)
			(layers "F.Cu" "F.Mask" "F.Paste")
			(net "SSD12_LED_ISO_N")
		)
	)
	(footprint ""
		(layer "F.Cu")
		(at 217.756486 -20.467574 180)
		(property "Reference" "R1678"
			(at 0 0 180)
			(layer "F.SilkS")
			(hide yes)
			(effects
				(font
					(size 1.27 1.27)
				)
			)
		)
		(property "Value" ""
			(at 0 0 180)
			(layer "F.Fab")
			(effects
				(font
					(size 1.27 1.27)
				)
			)
		)
		(duplicate_pad_numbers_are_jumpers no)
		(fp_line
			(start 0.7874 0.4064)
			(end -0.7874 0.4064)
			(stroke
				(width 0.1524)
				(type default)
			)
			(layer "F.SilkS")
		)
		(fp_line
			(start 0.7874 -0.4064)
			(end 0.7874 0.4064)
			(stroke
				(width 0.1524)
				(type default)
			)
			(layer "F.SilkS")
		)
		(fp_line
			(start -0.7874 0.4064)
			(end -0.7874 -0.4064)
			(stroke
				(width 0.1524)
				(type default)
			)
			(layer "F.SilkS")
		)
		(fp_line
			(start -0.7874 -0.4064)
			(end 0.7874 -0.4064)
			(stroke
				(width 0.1524)
				(type default)
			)
			(layer "F.SilkS")
		)
		(fp_line
			(start 0.67945 0.3048)
			(end 0.120396 0.3048)
			(stroke
				(width 0.1)
				(type default)
			)
			(layer "F.Fab")
		)
		(fp_line
			(start 0.67945 -0.3048)
			(end 0.67945 0.3048)
			(stroke
				(width 0.1)
				(type default)
			)
			(layer "F.Fab")
		)
		(fp_line
			(start 0.12065 -0.2794)
			(end 0.12065 -0.3048)
			(stroke
				(width 0.1)
				(type default)
			)
			(layer "F.Fab")
		)
		(fp_line
			(start 0.12065 -0.3048)
			(end 0.67945 -0.3048)
			(stroke
				(width 0.1)
				(type default)
			)
			(layer "F.Fab")
		)
		(fp_line
			(start 0.120396 0.3048)
			(end 0.120396 0.2794)
			(stroke
				(width 0.1)
				(type default)
			)
			(layer "F.Fab")
		)
		(fp_line
			(start 0.120396 0.2794)
			(end -0.12065 0.2794)
			(stroke
				(width 0.1)
				(type default)
			)
			(layer "F.Fab")
		)
		(fp_line
			(start -0.12065 0.3048)
			(end -0.67945 0.3048)
			(stroke
				(width 0.1)
				(type default)
			)
			(layer "F.Fab")
		)
		(fp_line
			(start -0.12065 0.2794)
			(end -0.12065 0.3048)
			(stroke
				(width 0.1)
				(type default)
			)
			(layer "F.Fab")
		)
		(fp_line
			(start -0.12065 -0.2794)
			(end 0.12065 -0.2794)
			(stroke
				(width 0.1)
				(type default)
			)
			(layer "F.Fab")
		)
		(fp_line
			(start -0.12065 -0.305054)
			(end -0.12065 -0.2794)
			(stroke
				(width 0.1)
				(type default)
			)
			(layer "F.Fab")
		)
		(fp_line
			(start -0.67945 0.3048)
			(end -0.67945 -0.305054)
			(stroke
				(width 0.1)
				(type default)
			)
			(layer "F.Fab")
		)
		(fp_line
			(start -0.67945 -0.305054)
			(end -0.12065 -0.305054)
			(stroke
				(width 0.1)
				(type default)
			)
			(layer "F.Fab")
		)
		(pad "1" smd circle
			(at -0.40005 0 180)
			(size 0 0)
			(layers "F.Cu" "F.Mask" "F.Paste")
			(net "P3V3_SSD7")
		)
		(pad "2" smd circle
			(at 0.40005 0 180)
			(size 0 0)
			(layers "F.Cu" "F.Mask" "F.Paste")
			(net "SMB_ISO_SSD7_SDA")
		)
	)
)
